(kicad_pcb
	(version 20260206)
	(generator "pcbnew")
	(generator_version "10.0")
	(general
		(thickness 1.6)
		(legacy_teardrops no)
	)
	(paper "A4")
	(title_block
		(title "03242023_DA0F0TMBIJ0_F0T_Motherboard_J_brd_V01_OCP.brd")
		(comment 1 "Grand Teton / footprints 2583-2589 of 6105")
	)
	(layers
		(0 "F.Cu" signal "TOP")
		(4 "In1.Cu" signal "GND")
		(6 "In2.Cu" signal "IN1")
		(8 "In3.Cu" signal "GND1")
		(10 "In4.Cu" signal "IN2")
		(12 "In5.Cu" signal "GND2")
		(14 "In6.Cu" signal "IN3")
		(16 "In7.Cu" signal "GND3")
		(18 "In8.Cu" signal "VCC")
		(20 "In9.Cu" signal "VCC1")
		(22 "In10.Cu" signal "GND4")
		(24 "In11.Cu" signal "IN4")
		(26 "In12.Cu" signal "GND5")
		(28 "In13.Cu" signal "IN5")
		(30 "In14.Cu" signal "GND6")
		(32 "In15.Cu" signal "IN6")
		(34 "In16.Cu" signal "GND7")
		(2 "B.Cu" signal "BOTTOM")
		(9 "F.Adhes" user "F.Adhesive")
		(11 "B.Adhes" user "B.Adhesive")
		(13 "F.Paste" user "Package Geometry/Pastemask Top")
		(15 "B.Paste" user "Package Geometry/Pastemask Bottom")
		(5 "F.SilkS" user "Ref Des/Silkscreen Top")
		(7 "B.SilkS" user "Ref Des/Silkscreen Bottom")
		(1 "F.Mask" user "Board Geometry/Soldermask Top")
		(3 "B.Mask" user "Board Geometry/Soldermask Bottom")
		(17 "Dwgs.User" user "User.Drawings")
		(19 "Cmts.User" user "User.Comments")
		(21 "Eco1.User" user "User.Eco1")
		(23 "Eco2.User" user "User.Eco2")
		(25 "Edge.Cuts" user "Board Geometry/Outline")
		(27 "Margin" user)
		(31 "F.CrtYd" user "Package Geometry/Place Bound Top")
		(29 "B.CrtYd" user "Package Geometry/Place Bound Bottom")
		(35 "F.Fab" user "Ref Des/Assembly Top")
		(33 "B.Fab" user "Ref Des/Assembly Bottom")
	)
	(footprint ""
		(layer "F.Cu")
		(at 410.488384 -17.612614 90)
		(property "Reference" "C853"
			(at 0 0 90)
			(layer "F.SilkS")
			(hide yes)
			(effects
				(font
					(size 1.27 1.27)
				)
			)
		)
		(property "Value" ""
			(at 0 0 90)
			(layer "F.Fab")
			(effects
				(font
					(size 1.27 1.27)
				)
			)
		)
		(duplicate_pad_numbers_are_jumpers no)
		(fp_line
			(start 0.299974 -0.150114)
			(end 0.299974 0.150114)
			(stroke
				(width 0.1)
				(type default)
			)
			(layer "F.Fab")
		)
		(fp_line
			(start -0.299974 -0.150114)
			(end 0.299974 -0.150114)
			(stroke
				(width 0.1)
				(type default)
			)
			(layer "F.Fab")
		)
		(fp_line
			(start 0.299974 0.150114)
			(end -0.299974 0.150114)
			(stroke
				(width 0.1)
				(type default)
			)
			(layer "F.Fab")
		)
		(fp_line
			(start -0.299974 0.150114)
			(end -0.299974 -0.150114)
			(stroke
				(width 0.1)
				(type default)
			)
			(layer "F.Fab")
		)
		(pad "1" smd rect
			(at -0.2667 0 90)
			(size 0.3048 0.381)
			(layers "F.Cu" "F.Mask" "F.Paste")
			(net "P5E_CPU0_PE1_TX_C_DP<8>")
		)
		(pad "2" smd rect
			(at 0.2667 0 90)
			(size 0.3048 0.381)
			(layers "F.Cu" "F.Mask" "F.Paste")
			(net "P5E_CPU0_PE1_TX_DP<8>")
		)
	)
	(footprint ""
		(layer "F.Cu")
		(at 19.927824 -396.011908 90)
		(property "Reference" "C1871"
			(at 0 0 90)
			(layer "F.SilkS")
			(hide yes)
			(effects
				(font
					(size 1.27 1.27)
				)
			)
		)
		(property "Value" ""
			(at 0 0 90)
			(layer "F.Fab")
			(effects
				(font
					(size 1.27 1.27)
				)
			)
		)
		(duplicate_pad_numbers_are_jumpers no)
		(fp_line
			(start 0.7874 -0.4064)
			(end 0.7874 0.4064)
			(stroke
				(width 0.1524)
				(type default)
			)
			(layer "F.SilkS")
		)
		(fp_line
			(start -0.7874 -0.4064)
			(end -0.018288 -0.4064)
			(stroke
				(width 0.1524)
				(type default)
			)
			(layer "F.SilkS")
		)
		(fp_line
			(start 0.7874 0.4064)
			(end -0.7874 0.4064)
			(stroke
				(width 0.1524)
				(type default)
			)
			(layer "F.SilkS")
		)
		(fp_line
			(start 0.6858 -0.3048)
			(end 0.6858 0.3048)
			(stroke
				(width 0.1)
				(type default)
			)
			(layer "F.Fab")
		)
		(fp_line
			(start 0.1016 -0.3048)
			(end 0.6858 -0.3048)
			(stroke
				(width 0.1)
				(type default)
			)
			(layer "F.Fab")
		)
		(fp_line
			(start -0.1016 -0.3048)
			(end -0.1016 -0.2794)
			(stroke
				(width 0.1)
				(type default)
			)
			(layer "F.Fab")
		)
		(fp_line
			(start -0.6858 -0.3048)
			(end -0.1016 -0.3048)
			(stroke
				(width 0.1)
				(type default)
			)
			(layer "F.Fab")
		)
		(fp_line
			(start 0.1016 -0.2794)
			(end 0.1016 -0.3048)
			(stroke
				(width 0.1)
				(type default)
			)
			(layer "F.Fab")
		)
		(fp_line
			(start -0.1016 -0.2794)
			(end 0.1016 -0.2794)
			(stroke
				(width 0.1)
				(type default)
			)
			(layer "F.Fab")
		)
		(fp_line
			(start 0.1016 0.2794)
			(end -0.1016 0.2794)
			(stroke
				(width 0.1)
				(type default)
			)
			(layer "F.Fab")
		)
		(fp_line
			(start -0.1016 0.2794)
			(end -0.1016 0.3048)
			(stroke
				(width 0.1)
				(type default)
			)
			(layer "F.Fab")
		)
		(fp_line
			(start 0.6858 0.3048)
			(end 0.1016 0.3048)
			(stroke
				(width 0.1)
				(type default)
			)
			(layer "F.Fab")
		)
		(fp_line
			(start 0.1016 0.3048)
			(end 0.1016 0.2794)
			(stroke
				(width 0.1)
				(type default)
			)
			(layer "F.Fab")
		)
		(fp_line
			(start -0.1016 0.3048)
			(end -0.6858 0.3048)
			(stroke
				(width 0.1)
				(type default)
			)
			(layer "F.Fab")
		)
		(fp_line
			(start -0.6858 0.3048)
			(end -0.6858 -0.3048)
			(stroke
				(width 0.1)
				(type default)
			)
			(layer "F.Fab")
		)
		(pad "1" smd rect
			(at -0.40005 0 270)
			(size 0.4572 0.508)
			(layers "F.Cu" "F.Mask" "F.Paste")
			(net "P2E_MB_BMC_TX_BUF_DN<0>")
		)
		(pad "2" smd rect
			(at 0.40005 0 270)
			(size 0.4572 0.508)
			(layers "F.Cu" "F.Mask" "F.Paste")
			(net "P2E_MB_BMC_TX_BUF_C_DN<0>")
		)
	)
	(footprint ""
		(layer "F.Cu")
		(at 54.995318 -402.371052 -90)
		(property "Reference" "C715"
			(at 0 0 270)
			(layer "F.SilkS")
			(hide yes)
			(effects
				(font
					(size 1.27 1.27)
				)
			)
		)
		(property "Value" ""
			(at 0 0 270)
			(layer "F.Fab")
			(effects
				(font
					(size 1.27 1.27)
				)
			)
		)
		(duplicate_pad_numbers_are_jumpers no)
		(fp_line
			(start -0.299974 0.150114)
			(end -0.299974 -0.150114)
			(stroke
				(width 0.1)
				(type default)
			)
			(layer "F.Fab")
		)
		(fp_line
			(start 0.299974 0.150114)
			(end -0.299974 0.150114)
			(stroke
				(width 0.1)
				(type default)
			)
			(layer "F.Fab")
		)
		(fp_line
			(start -0.299974 -0.150114)
			(end 0.299974 -0.150114)
			(stroke
				(width 0.1)
				(type default)
			)
			(layer "F.Fab")
		)
		(fp_line
			(start 0.299974 -0.150114)
			(end 0.299974 0.150114)
			(stroke
				(width 0.1)
				(type default)
			)
			(layer "F.Fab")
		)
		(pad "1" smd rect
			(at -0.2667 0 270)
			(size 0.3048 0.381)
			(layers "F.Cu" "F.Mask" "F.Paste")
			(net "P5E_CPU1_PE0_TX_C_DP<13>")
		)
		(pad "2" smd rect
			(at 0.2667 0 270)
			(size 0.3048 0.381)
			(layers "F.Cu" "F.Mask" "F.Paste")
			(net "P5E_CPU1_PE0_TX_DP<13>")
		)
	)
	(footprint ""
		(layer "F.Cu")
		(at 49.755552 -155.186634 90)
		(property "Reference" "PR1726"
			(at 0 0 90)
			(layer "F.SilkS")
			(hide yes)
			(effects
				(font
					(size 1.27 1.27)
				)
			)
		)
		(property "Value" ""
			(at 0 0 90)
			(layer "F.Fab")
			(effects
				(font
					(size 1.27 1.27)
				)
			)
		)
		(duplicate_pad_numbers_are_jumpers no)
		(fp_line
			(start 0.7874 -0.4064)
			(end 0.7874 0.4064)
			(stroke
				(width 0.1524)
				(type default)
			)
			(layer "F.SilkS")
		)
		(fp_line
			(start -0.7874 -0.4064)
			(end 0.7874 -0.4064)
			(stroke
				(width 0.1524)
				(type default)
			)
			(layer "F.SilkS")
		)
		(fp_line
			(start 0.7874 0.4064)
			(end -0.7874 0.4064)
			(stroke
				(width 0.1524)
				(type default)
			)
			(layer "F.SilkS")
		)
		(fp_line
			(start -0.7874 0.4064)
			(end -0.7874 -0.4064)
			(stroke
				(width 0.1524)
				(type default)
			)
			(layer "F.SilkS")
		)
		(fp_line
			(start -0.12065 -0.305054)
			(end -0.12065 -0.2794)
			(stroke
				(width 0.1)
				(type default)
			)
			(layer "F.Fab")
		)
		(fp_line
			(start -0.67945 -0.305054)
			(end -0.12065 -0.305054)
			(stroke
				(width 0.1)
				(type default)
			)
			(layer "F.Fab")
		)
		(fp_line
			(start 0.67945 -0.3048)
			(end 0.67945 0.3048)
			(stroke
				(width 0.1)
				(type default)
			)
			(layer "F.Fab")
		)
		(fp_line
			(start 0.12065 -0.3048)
			(end 0.67945 -0.3048)
			(stroke
				(width 0.1)
				(type default)
			)
			(layer "F.Fab")
		)
		(fp_line
			(start 0.12065 -0.2794)
			(end 0.12065 -0.3048)
			(stroke
				(width 0.1)
				(type default)
			)
			(layer "F.Fab")
		)
		(fp_line
			(start -0.12065 -0.2794)
			(end 0.12065 -0.2794)
			(stroke
				(width 0.1)
				(type default)
			)
			(layer "F.Fab")
		)
		(fp_line
			(start 0.120396 0.2794)
			(end -0.12065 0.2794)
			(stroke
				(width 0.1)
				(type default)
			)
			(layer "F.Fab")
		)
		(fp_line
			(start -0.12065 0.2794)
			(end -0.12065 0.3048)
			(stroke
				(width 0.1)
				(type default)
			)
			(layer "F.Fab")
		)
		(fp_line
			(start 0.67945 0.3048)
			(end 0.120396 0.3048)
			(stroke
				(width 0.1)
				(type default)
			)
			(layer "F.Fab")
		)
		(fp_line
			(start 0.120396 0.3048)
			(end 0.120396 0.2794)
			(stroke
				(width 0.1)
				(type default)
			)
			(layer "F.Fab")
		)
		(fp_line
			(start -0.12065 0.3048)
			(end -0.67945 0.3048)
			(stroke
				(width 0.1)
				(type default)
			)
			(layer "F.Fab")
		)
		(fp_line
			(start -0.67945 0.3048)
			(end -0.67945 -0.305054)
			(stroke
				(width 0.1)
				(type default)
			)
			(layer "F.Fab")
		)
		(pad "1" smd circle
			(at -0.40005 0 90)
			(size 0 0)
			(layers "F.Cu" "F.Mask" "F.Paste")
			(net "PVCCINFAON_CPU1_LSET1")
		)
		(pad "2" smd circle
			(at 0.40005 0 90)
			(size 0 0)
			(layers "F.Cu" "F.Mask" "F.Paste")
			(net "GND")
		)
	)
	(footprint ""
		(layer "F.Cu")
		(at 339.483446 -27.92603 -90)
		(property "Reference" "R770"
			(at 0 0 270)
			(layer "F.SilkS")
			(hide yes)
			(effects
				(font
					(size 1.27 1.27)
				)
			)
		)
		(property "Value" ""
			(at 0 0 270)
			(layer "F.Fab")
			(effects
				(font
					(size 1.27 1.27)
				)
			)
		)
		(duplicate_pad_numbers_are_jumpers no)
		(fp_line
			(start -0.7874 0.4064)
			(end -0.7874 -0.4064)
			(stroke
				(width 0.1524)
				(type default)
			)
			(layer "F.SilkS")
		)
		(fp_line
			(start 0.7874 0.4064)
			(end -0.7874 0.4064)
			(stroke
				(width 0.1524)
				(type default)
			)
			(layer "F.SilkS")
		)
		(fp_line
			(start -0.7874 -0.4064)
			(end 0.7874 -0.4064)
			(stroke
				(width 0.1524)
				(type default)
			)
			(layer "F.SilkS")
		)
		(fp_line
			(start 0.7874 -0.4064)
			(end 0.7874 0.4064)
			(stroke
				(width 0.1524)
				(type default)
			)
			(layer "F.SilkS")
		)
		(fp_line
			(start -0.67945 0.3048)
			(end -0.67945 -0.305054)
			(stroke
				(width 0.1)
				(type default)
			)
			(layer "F.Fab")
		)
		(fp_line
			(start -0.12065 0.3048)
			(end -0.67945 0.3048)
			(stroke
				(width 0.1)
				(type default)
			)
			(layer "F.Fab")
		)
		(fp_line
			(start 0.120396 0.3048)
			(end 0.120396 0.2794)
			(stroke
				(width 0.1)
				(type default)
			)
			(layer "F.Fab")
		)
		(fp_line
			(start 0.67945 0.3048)
			(end 0.120396 0.3048)
			(stroke
				(width 0.1)
				(type default)
			)
			(layer "F.Fab")
		)
		(fp_line
			(start -0.12065 0.2794)
			(end -0.12065 0.3048)
			(stroke
				(width 0.1)
				(type default)
			)
			(layer "F.Fab")
		)
		(fp_line
			(start 0.120396 0.2794)
			(end -0.12065 0.2794)
			(stroke
				(width 0.1)
				(type default)
			)
			(layer "F.Fab")
		)
		(fp_line
			(start -0.12065 -0.2794)
			(end 0.12065 -0.2794)
			(stroke
				(width 0.1)
				(type default)
			)
			(layer "F.Fab")
		)
		(fp_line
			(start 0.12065 -0.2794)
			(end 0.12065 -0.3048)
			(stroke
				(width 0.1)
				(type default)
			)
			(layer "F.Fab")
		)
		(fp_line
			(start 0.12065 -0.3048)
			(end 0.67945 -0.3048)
			(stroke
				(width 0.1)
				(type default)
			)
			(layer "F.Fab")
		)
		(fp_line
			(start 0.67945 -0.3048)
			(end 0.67945 0.3048)
			(stroke
				(width 0.1)
				(type default)
			)
			(layer "F.Fab")
		)
		(fp_line
			(start -0.67945 -0.305054)
			(end -0.12065 -0.305054)
			(stroke
				(width 0.1)
				(type default)
			)
			(layer "F.Fab")
		)
		(fp_line
			(start -0.12065 -0.305054)
			(end -0.12065 -0.2794)
			(stroke
				(width 0.1)
				(type default)
			)
			(layer "F.Fab")
		)
		(pad "1" smd circle
			(at -0.40005 0 270)
			(size 0 0)
			(layers "F.Cu" "F.Mask" "F.Paste")
			(net "PU_OC5_USB_N")
		)
		(pad "2" smd circle
			(at 0.40005 0 270)
			(size 0 0)
			(layers "F.Cu" "F.Mask" "F.Paste")
			(net "P3V3_AUX")
		)
	)
	(footprint ""
		(layer "F.Cu")
		(at 51.593496 -115.12677)
		(property "Reference" "R3724"
			(at 0 0 0)
			(layer "F.SilkS")
			(hide yes)
			(effects
				(font
					(size 1.27 1.27)
				)
			)
		)
		(property "Value" ""
			(at 0 0 0)
			(layer "F.Fab")
			(effects
				(font
					(size 1.27 1.27)
				)
			)
		)
		(duplicate_pad_numbers_are_jumpers no)
		(fp_line
			(start -0.7874 -0.4064)
			(end 0.7874 -0.4064)
			(stroke
				(width 0.1524)
				(type default)
			)
			(layer "F.SilkS")
		)
		(fp_line
			(start -0.7874 0.4064)
			(end -0.7874 -0.4064)
			(stroke
				(width 0.1524)
				(type default)
			)
			(layer "F.SilkS")
		)
		(fp_line
			(start 0.7874 -0.4064)
			(end 0.7874 0.4064)
			(stroke
				(width 0.1524)
				(type default)
			)
			(layer "F.SilkS")
		)
		(fp_line
			(start 0.7874 0.4064)
			(end -0.7874 0.4064)
			(stroke
				(width 0.1524)
				(type default)
			)
			(layer "F.SilkS")
		)
		(fp_line
			(start -0.67945 -0.305054)
			(end -0.12065 -0.305054)
			(stroke
				(width 0.1)
				(type default)
			)
			(layer "F.Fab")
		)
		(fp_line
			(start -0.67945 0.3048)
			(end -0.67945 -0.305054)
			(stroke
				(width 0.1)
				(type default)
			)
			(layer "F.Fab")
		)
		(fp_line
			(start -0.12065 -0.305054)
			(end -0.12065 -0.2794)
			(stroke
				(width 0.1)
				(type default)
			)
			(layer "F.Fab")
		)
		(fp_line
			(start -0.12065 -0.2794)
			(end 0.12065 -0.2794)
			(stroke
				(width 0.1)
				(type default)
			)
			(layer "F.Fab")
		)
		(fp_line
			(start -0.12065 0.2794)
			(end -0.12065 0.3048)
			(stroke
				(width 0.1)
				(type default)
			)
			(layer "F.Fab")
		)
		(fp_line
			(start -0.12065 0.3048)
			(end -0.67945 0.3048)
			(stroke
				(width 0.1)
				(type default)
			)
			(layer "F.Fab")
		)
		(fp_line
			(start 0.120396 0.2794)
			(end -0.12065 0.2794)
			(stroke
				(width 0.1)
				(type default)
			)
			(layer "F.Fab")
		)
		(fp_line
			(start 0.120396 0.3048)
			(end 0.120396 0.2794)
			(stroke
				(width 0.1)
				(type default)
			)
			(layer "F.Fab")
		)
		(fp_line
			(start 0.12065 -0.3048)
			(end 0.67945 -0.3048)
			(stroke
				(width 0.1)
				(type default)
			)
			(layer "F.Fab")
		)
		(fp_line
			(start 0.12065 -0.2794)
			(end 0.12065 -0.3048)
			(stroke
				(width 0.1)
				(type default)
			)
			(layer "F.Fab")
		)
		(fp_line
			(start 0.67945 -0.3048)
			(end 0.67945 0.3048)
			(stroke
				(width 0.1)
				(type default)
			)
			(layer "F.Fab")
		)
		(fp_line
			(start 0.67945 0.3048)
			(end 0.120396 0.3048)
			(stroke
				(width 0.1)
				(type default)
			)
			(layer "F.Fab")
		)
		(pad "1" smd circle
			(at -0.40005 0)
			(size 0 0)
			(layers "F.Cu" "F.Mask" "F.Paste")
			(net "P3V3_AUX")
		)
		(pad "2" smd circle
			(at 0.40005 0)
			(size 0 0)
			(layers "F.Cu" "F.Mask" "F.Paste")
			(net "SMB_VR_3V3AUX_SDA")
		)
	)
	(footprint ""
		(layer "F.Cu")
		(at 148.197824 -53.436012)
		(property "Reference" "R3610"
			(at 0 0 0)
			(layer "F.SilkS")
			(hide yes)
			(effects
				(font
					(size 1.27 1.27)
				)
			)
		)
		(property "Value" ""
			(at 0 0 0)
			(layer "F.Fab")
			(effects
				(font
					(size 1.27 1.27)
				)
			)
		)
		(duplicate_pad_numbers_are_jumpers no)
		(fp_line
			(start -0.7874 -0.4064)
			(end 0.7874 -0.4064)
			(stroke
				(width 0.1524)
				(type default)
			)
			(layer "F.SilkS")
		)
		(fp_line
			(start -0.7874 0.4064)
			(end -0.7874 -0.4064)
			(stroke
				(width 0.1524)
				(type default)
			)
			(layer "F.SilkS")
		)
		(fp_line
			(start 0.7874 -0.4064)
			(end 0.7874 0.4064)
			(stroke
				(width 0.1524)
				(type default)
			)
			(layer "F.SilkS")
		)
		(fp_line
			(start 0.7874 0.4064)
			(end -0.7874 0.4064)
			(stroke
				(width 0.1524)
				(type default)
			)
			(layer "F.SilkS")
		)
		(fp_line
			(start -0.67945 -0.305054)
			(end -0.12065 -0.305054)
			(stroke
				(width 0.1)
				(type default)
			)
			(layer "F.Fab")
		)
		(fp_line
			(start -0.67945 0.3048)
			(end -0.67945 -0.305054)
			(stroke
				(width 0.1)
				(type default)
			)
			(layer "F.Fab")
		)
		(fp_line
			(start -0.12065 -0.305054)
			(end -0.12065 -0.2794)
			(stroke
				(width 0.1)
				(type default)
			)
			(layer "F.Fab")
		)
		(fp_line
			(start -0.12065 -0.2794)
			(end 0.12065 -0.2794)
			(stroke
				(width 0.1)
				(type default)
			)
			(layer "F.Fab")
		)
		(fp_line
			(start -0.12065 0.2794)
			(end -0.12065 0.3048)
			(stroke
				(width 0.1)
				(type default)
			)
			(layer "F.Fab")
		)
		(fp_line
			(start -0.12065 0.3048)
			(end -0.67945 0.3048)
			(stroke
				(width 0.1)
				(type default)
			)
			(layer "F.Fab")
		)
		(fp_line
			(start 0.120396 0.2794)
			(end -0.12065 0.2794)
			(stroke
				(width 0.1)
				(type default)
			)
			(layer "F.Fab")
		)
		(fp_line
			(start 0.120396 0.3048)
			(end 0.120396 0.2794)
			(stroke
				(width 0.1)
				(type default)
			)
			(layer "F.Fab")
		)
		(fp_line
			(start 0.12065 -0.3048)
			(end 0.67945 -0.3048)
			(stroke
				(width 0.1)
				(type default)
			)
			(layer "F.Fab")
		)
		(fp_line
			(start 0.12065 -0.2794)
			(end 0.12065 -0.3048)
			(stroke
				(width 0.1)
				(type default)
			)
			(layer "F.Fab")
		)
		(fp_line
			(start 0.67945 -0.3048)
			(end 0.67945 0.3048)
			(stroke
				(width 0.1)
				(type default)
			)
			(layer "F.Fab")
		)
		(fp_line
			(start 0.67945 0.3048)
			(end 0.120396 0.3048)
			(stroke
				(width 0.1)
				(type default)
			)
			(layer "F.Fab")
		)
		(pad "1" smd circle
			(at -0.40005 0)
			(size 0 0)
			(layers "F.Cu" "F.Mask" "F.Paste")
			(net "GND")
		)
		(pad "2" smd circle
			(at 0.40005 0)
			(size 0 0)
			(layers "F.Cu" "F.Mask" "F.Paste")
			(net "INA230_4_A1")
		)
	)
)
